(kicad_pcb
	(version 20221018)
	(generator pcbnew)
	(general
    (thickness 1.518)
  )
	(paper "A4")
	(title_block
    (title "Kria K26 Devboard")
    (date "2024-03-26")
    (rev "1.2.5")
    (comment 1 "www.antmicro.com")
    (comment 2 "Antmicro Ltd.")
		(comment 9 "footprints 79-82 of 660")
	)
	(layers
    (0 "F.Cu" mixed)
    (1 "In1.Cu" power)
    (2 "In2.Cu" mixed)
    (3 "In3.Cu" power)
    (4 "In4.Cu" mixed)
    (5 "In5.Cu" power)
    (6 "In6.Cu" mixed)
    (31 "B.Cu" power)
    (32 "B.Adhes" user "B.Adhesive")
    (33 "F.Adhes" user "F.Adhesive")
    (34 "B.Paste" user)
    (35 "F.Paste" user)
    (36 "B.SilkS" user "B.Silkscreen")
    (37 "F.SilkS" user "F.Silkscreen")
    (38 "B.Mask" user)
    (39 "F.Mask" user)
    (40 "Dwgs.User" user "User.Drawings")
    (41 "Cmts.User" user "User.Comments")
    (42 "Eco1.User" user "User.Eco1")
    (43 "Eco2.User" user "User.Eco2")
    (44 "Edge.Cuts" user)
    (45 "Margin" user)
    (46 "B.CrtYd" user "B.Courtyard")
    (47 "F.CrtYd" user "F.Courtyard")
    (48 "B.Fab" user)
    (49 "F.Fab" user)
  )
	(footprint "kria-k26-devboard-footprints:SOT-563" (layer "F.Cu")
    (at 146.72 61.9 90)
    (property "Author" "Antmicro")
    (property "License" "Apache-2.0")
    (property "MPN" "82400152")
    (property "Manufacturer" "Würth Elektronik")
    (property "Sheetfile" "usbc-socket.kicad_sch")
    (property "Sheetname" "USB-C socket")
    (property "ki_description" "TVS diode")
    (property "ki_keywords" "SMT, DIODE, IC, ESD, TVS")
    (attr smd)
    (fp_text reference "U60" (at -1.92 -1.12 180) (layer "F.SilkS")
        (effects (font (size 0.7 0.7) (thickness 0.15)) (justify left bottom))
    )
    (fp_text value "82400152" (at 0 2 90) (layer "F.Fab") hide
        (effects (font (size 0.7 0.7) (thickness 0.15)) (justify left bottom))
    )
    (fp_text user "Author: Antmicro" (at -1.299 6.124 90) (layer "F.Fab") hide
        (effects (font (size 0.7 0.7) (thickness 0.15)) (justify left bottom))
    )
    (fp_text user "License: Apache-2.0" (at -1.299 4.924 90) (layer "F.Fab") hide
        (effects (font (size 0.7 0.7) (thickness 0.15)) (justify left bottom))
    )
    (fp_text user "${REFERENCE}" (at -1.299 7.323 90) (layer "F.Fab") hide
        (effects (font (size 0.7 0.7) (thickness 0.15)) (justify left bottom))
    )
    (fp_line (start -0.778 0.776) (end -0.778 0.949)
      (stroke (width 0.15) (type solid)) (layer "F.SilkS"))
    (fp_line (start -0.778 0.949) (end -0.424 0.949)
      (stroke (width 0.15) (type solid)) (layer "F.SilkS"))
    (fp_line (start -0.499 -0.974) (end -0.724 -0.778)
      (stroke (width 0.15) (type solid)) (layer "F.SilkS"))
    (fp_line (start 0.776 -0.974) (end 0.526 -0.974)
      (stroke (width 0.15) (type solid)) (layer "F.SilkS"))
    (fp_line (start 0.776 -0.974) (end 0.776 -0.778)
      (stroke (width 0.15) (type solid)) (layer "F.SilkS"))
    (fp_line (start 0.776 0.776) (end 0.776 0.972)
      (stroke (width 0.15) (type solid)) (layer "F.SilkS"))
    (fp_line (start 0.776 0.972) (end 0.526 0.972)
      (stroke (width 0.15) (type solid)) (layer "F.SilkS"))
    (fp_circle (center -0.903 -0.999) (end -0.952 -0.95)
      (stroke (width 0.15) (type solid)) (fill solid) (layer "F.SilkS"))
    (fp_rect (start 1.19 -1.12) (end -1.2 1.1)
      (stroke (width 0.05) (type solid)) (fill none) (layer "F.CrtYd"))
    (fp_line (start -0.653 -0.678) (end -0.653 0.847)
      (stroke (width 0.15) (type solid)) (layer "F.Fab"))
    (fp_line (start -0.453 -0.849) (end -0.653 -0.678)
      (stroke (width 0.15) (type solid)) (layer "F.Fab"))
    (fp_line (start -0.453 -0.849) (end 0.651 -0.849)
      (stroke (width 0.15) (type solid)) (layer "F.Fab"))
    (fp_line (start 0.651 -0.849) (end 0.651 0.847)
      (stroke (width 0.15) (type solid)) (layer "F.Fab"))
    (fp_line (start 0.651 0.847) (end -0.653 0.847)
      (stroke (width 0.15) (type solid)) (layer "F.Fab"))
    (pad "1" smd roundrect (at -0.749 -0.499) (size 0.3 0.6) (layers "F.Cu" "F.Paste" "F.Mask") (roundrect_rratio 0.25)
      (net 189 "/Debug and JTAG/USBC_N") (pintype "passive"))
    (pad "2" smd roundrect (at -0.749 0.001) (size 0.3 0.6) (layers "F.Cu" "F.Paste" "F.Mask") (roundrect_rratio 0.25)
      (net 1 "GND") (pintype "passive"))
    (pad "3" smd roundrect (at -0.749 0.497) (size 0.3 0.6) (layers "F.Cu" "F.Paste" "F.Mask") (roundrect_rratio 0.25)
      (net 188 "/Debug and JTAG/USBC_P") (pintype "passive"))
    (pad "4" smd roundrect (at 0.747 0.497) (size 0.3 0.6) (layers "F.Cu" "F.Paste" "F.Mask") (roundrect_rratio 0.25)
      (net 299 "/Power Supply/USB-C socket/USBC_TVS_P") (pintype "passive"))
    (pad "5" smd roundrect (at 0.747 0.001) (size 0.3 0.6) (layers "F.Cu" "F.Paste" "F.Mask") (roundrect_rratio 0.25)
      (net 757 "unconnected-(U60-Pad5)") (pintype "passive+no_connect"))
    (pad "6" smd roundrect (at 0.747 -0.499) (size 0.3 0.6) (layers "F.Cu" "F.Paste" "F.Mask") (roundrect_rratio 0.25)
      (net 298 "/Power Supply/USB-C socket/USBC_TVS_N") (pintype "passive"))
  )
	(footprint "kria-k26-devboard-footprints:SOT-23-5" (layer "F.Cu")
    (at 102.825 140.925 180)
    (property "Author" "Antmicro")
    (property "License" "Apache-2.0")
    (property "MPN" "TPS3840PH30DBVR")
    (property "Manufacturer" "Texas Instruments")
    (property "Sheetfile" "reset.kicad_sch")
    (property "Sheetname" "Reset logic")
    (property "ki_description" "Voltage supervisor")
    (property "ki_keywords" "SMT, PMIC, IC, CONTROLLER")
    (attr smd)
    (fp_text reference "U31" (at 0.855 -0.345) (layer "F.SilkS")
        (effects (font (size 0.7 0.7) (thickness 0.15)) (justify right bottom))
    )
    (fp_text value "TPS3840PH30DBVR" (at 0.002 2.799) (layer "F.Fab") hide
        (effects (font (size 0.7 0.7) (thickness 0.15)) (justify right bottom))
    )
    (fp_text user "${REFERENCE}" (at -1.898 4.299) (layer "F.Fab") hide
        (effects (font (size 0.7 0.7) (thickness 0.15)) (justify right bottom))
    )
    (fp_text user "License: Apache-2.0" (at -1.898 6.7) (layer "F.Fab") hide
        (effects (font (size 0.7 0.7) (thickness 0.15)) (justify right bottom))
    )
    (fp_text user "Author: Antmicro" (at -1.898 5.499) (layer "F.Fab") hide
        (effects (font (size 0.7 0.7) (thickness 0.15)) (justify right bottom))
    )
    (fp_line (start -0.85 1.6) (end -0.85 1.301)
      (stroke (width 0.15) (type solid)) (layer "F.SilkS"))
    (fp_line (start -0.8 -1.6) (end -0.8 -1.3)
      (stroke (width 0.15) (type solid)) (layer "F.SilkS"))
    (fp_line (start -0.8 -1.6) (end -0.5 -1.6)
      (stroke (width 0.15) (type solid)) (layer "F.SilkS"))
    (fp_line (start -0.55 1.6) (end -0.85 1.6)
      (stroke (width 0.15) (type solid)) (layer "F.SilkS"))
    (fp_line (start 0.8 -1.6) (end 0.5 -1.6)
      (stroke (width 0.15) (type solid)) (layer "F.SilkS"))
    (fp_line (start 0.8 -1.3) (end 0.8 -1.6)
      (stroke (width 0.15) (type solid)) (layer "F.SilkS"))
    (fp_line (start 0.8 0.55) (end 0.8 -0.55)
      (stroke (width 0.15) (type solid)) (layer "F.SilkS"))
    (fp_line (start 0.8 1.3) (end 0.8 1.599)
      (stroke (width 0.15) (type solid)) (layer "F.SilkS"))
    (fp_line (start 0.8 1.599) (end 0.549 1.599)
      (stroke (width 0.15) (type solid)) (layer "F.SilkS"))
    (fp_circle (center -1.25 -1.5) (end -1.2 -1.5)
      (stroke (width 0.15) (type solid)) (fill solid) (layer "F.SilkS"))
    (fp_rect (start 1.9 -1.76) (end -1.9 1.75)
      (stroke (width 0.05) (type solid)) (fill none) (layer "F.CrtYd"))
    (fp_line (start -0.398 -1.526) (end -0.874 -1.05)
      (stroke (width 0.15) (type solid)) (layer "F.Fab"))
    (fp_rect (start 0.874 1.523) (end -0.873 -1.525)
      (stroke (width 0.15) (type solid)) (fill none) (layer "F.Fab"))
    (pad "1" smd rect (at -1.351 -0.951 90) (size 0.55 1) (layers "F.Cu" "F.Paste" "F.Mask")
      (net 161 "/Reset logic/PS_RST") (pinfunction "RESET") (pintype "open_collector"))
    (pad "2" smd rect (at -1.351 0 90) (size 0.55 1) (layers "F.Cu" "F.Paste" "F.Mask")
      (net 15 "PS_3V3") (pinfunction "VDD") (pintype "power_in"))
    (pad "3" smd rect (at -1.351 0.949 90) (size 0.55 1) (layers "F.Cu" "F.Paste" "F.Mask")
      (net 1 "GND") (pinfunction "GND") (pintype "power_in"))
    (pad "4" smd rect (at 1.35 0.949 90) (size 0.55 1) (layers "F.Cu" "F.Paste" "F.Mask")
      (net 336 "Net-(U31-MR_N)") (pinfunction "MR_N") (pintype "input"))
    (pad "5" smd rect (at 1.35 -0.951 90) (size 0.55 1) (layers "F.Cu" "F.Paste" "F.Mask")
      (net 247 "Net-(U31-CT)") (pinfunction "CT") (pintype "input"))
  )
	(footprint "kria-k26-devboard-footprints:UQFN-16-1.8x2.6mm_P0.4mm_Texas_RSV0016A" (layer "F.Cu")
    (at 107.75 140.6 90)
    (descr "https://www.ti.com/lit/ds/symlink/sn74avch4t245-ep.pdf?ts=1679484181203&ref_url=https%253A%252F%252Fwww.ti.com%252Fproduct%252FSN74AVCH4T245-EP%253Futm_source%253Dgoogle%2526utm_medium%253Dcpc%2526utm_campaign%253Dasc-int-null-prodfolderdynamic-cpc-pf-google-wwe_int%2526utm_content%253Dprodfolddynamic%2526ds_k%253DDYNAMIC%2BSEARCH%2BADS%2526DCM%253Dyes%2526gclid%253DCjwKCAjwzuqgBhAcEiwAdj5dRvR_WgyvqqhLxMx8zfbFv2a6tg33JIMv01Bn4M1kA4JzW1nDDW7OzhoCRbkQAvD_BwE%2526gclsrc%253Daw.ds")
    (property "Author" "Antmicro")
    (property "License" "Apache-2.0")
    (property "MPN" "74AVC4T245RSVRG4")
    (property "Manufacturer" "Texas Instruments")
    (property "Sheetfile" "reset.kicad_sch")
    (property "Sheetname" "Reset logic")
    (property "ki_description" "Logic translator/level shifter")
    (property "ki_keywords" "SMT, LOGIC, IC, LEVEL-SHIFTER")
    (attr smd)
    (fp_text reference "U33" (at -1.25 -1.75 90) (layer "F.SilkS")
        (effects (font (size 0.7 0.7) (thickness 0.15)) (justify left bottom))
    )
    (fp_text value "74AVC4T245_UQFN" (at -1.25 2.5 90) (layer "F.Fab") hide
        (effects (font (size 0.7 0.7) (thickness 0.15)) (justify left bottom))
    )
    (fp_text user "." (at -1.45 -0.75 90) (layer "F.SilkS")
        (effects (font (size 0.7 0.7) (thickness 0.15)) (justify left bottom))
    )
    (fp_text user "License: Apache-2.0" (at -1.25 6.25 90) (layer "F.Fab") hide
        (effects (font (size 0.7 0.7) (thickness 0.15)) (justify left bottom))
    )
    (fp_text user "${REFERENCE}" (at -1.25 3.75 90) (layer "F.Fab") hide
        (effects (font (size 0.7 0.7) (thickness 0.15)) (justify left bottom))
    )
    (fp_text user "Author: Antmicro" (at -1.25 5 90) (layer "F.Fab") hide
        (effects (font (size 0.7 0.7) (thickness 0.15)) (justify left bottom))
    )
    (fp_line (start -0.9 1.2995) (end -0.9 0.8)
      (stroke (width 0.15) (type solid)) (layer "F.SilkS"))
    (fp_line (start -0.8 -1.3) (end -0.9 -1.3)
      (stroke (width 0.15) (type solid)) (layer "F.SilkS"))
    (fp_line (start -0.8 1.2995) (end -0.9 1.2995)
      (stroke (width 0.15) (type solid)) (layer "F.SilkS"))
    (fp_line (start 0.8 -1.3) (end 0.9 -1.3)
      (stroke (width 0.15) (type solid)) (layer "F.SilkS"))
    (fp_line (start 0.8 1.3) (end 0.899 1.3)
      (stroke (width 0.15) (type solid)) (layer "F.SilkS"))
    (fp_line (start 0.9 -1.3) (end 0.9 -0.8005)
      (stroke (width 0.15) (type solid)) (layer "F.SilkS"))
    (fp_line (start 0.9 0.8) (end 0.899 1.3)
      (stroke (width 0.15) (type solid)) (layer "F.SilkS"))
    (fp_rect (start -1.25 -1.65) (end 1.25 1.65)
      (stroke (width 0.05) (type solid)) (fill none) (layer "F.CrtYd"))
    (fp_line (start -0.902 1.3) (end -0.902 -1.301)
      (stroke (width 0.15) (type solid)) (layer "F.Fab"))
    (fp_line (start 0.9 -1.301) (end -0.902 -1.301)
      (stroke (width 0.15) (type solid)) (layer "F.Fab"))
    (fp_line (start 0.9 1.3) (end -0.902 1.3)
      (stroke (width 0.15) (type solid)) (layer "F.Fab"))
    (fp_line (start 0.9 1.3) (end 0.9 -1.301)
      (stroke (width 0.15) (type solid)) (layer "F.Fab"))
    (pad "1" smd roundrect (at -0.75 -0.6 90) (size 0.7 0.2) (layers "F.Cu" "F.Paste" "F.Mask") (roundrect_rratio 0.2272727273)
      (net 161 "/Reset logic/PS_RST") (pinfunction "1~{OE}") (pintype "input"))
    (pad "2" smd roundrect (at -0.802 -0.202 90) (size 0.6 0.2) (layers "F.Cu" "F.Paste" "F.Mask") (roundrect_rratio 0.2272727273)
      (net 17 "PS_1V8") (pinfunction "VCCB") (pintype "power_in"))
    (pad "3" smd roundrect (at -0.802 0.2 90) (size 0.6 0.2) (layers "F.Cu" "F.Paste" "F.Mask") (roundrect_rratio 0.2272727273)
      (net 15 "PS_3V3") (pinfunction "VCCA") (pintype "power_in"))
    (pad "4" smd roundrect (at -0.802 0.598 90) (size 0.6 0.2) (layers "F.Cu" "F.Paste" "F.Mask") (roundrect_rratio 0.2272727273)
      (net 1 "GND") (pinfunction "1DIR") (pintype "input"))
    (pad "5" smd roundrect (at -0.6 1.199 180) (size 0.6 0.2) (layers "F.Cu" "F.Paste" "F.Mask") (roundrect_rratio 0.2272727273)
      (net 1 "GND") (pinfunction "2DIR") (pintype "input"))
    (pad "6" smd roundrect (at -0.202 1.199 180) (size 0.6 0.2) (layers "F.Cu" "F.Paste" "F.Mask") (roundrect_rratio 0.2272727273)
      (net 675 "Net-(U33-1A1)") (pinfunction "1A1") (pintype "bidirectional"))
    (pad "7" smd roundrect (at 0.2 1.199 180) (size 0.6 0.2) (layers "F.Cu" "F.Paste" "F.Mask") (roundrect_rratio 0.2272727273)
      (net 677 "Net-(U33-1A2)") (pinfunction "1A2") (pintype "bidirectional"))
    (pad "8" smd roundrect (at 0.598 1.199 180) (size 0.6 0.2) (layers "F.Cu" "F.Paste" "F.Mask") (roundrect_rratio 0.2272727273)
      (net 678 "Net-(U33-2A1)") (pinfunction "2A1") (pintype "bidirectional"))
    (pad "9" smd roundrect (at 0.8 0.598 90) (size 0.6 0.2) (layers "F.Cu" "F.Paste" "F.Mask") (roundrect_rratio 0.2272727273)
      (net 679 "Net-(U33-2A2)") (pinfunction "2A2") (pintype "bidirectional"))
    (pad "10" smd roundrect (at 0.8 0.2 90) (size 0.6 0.2) (layers "F.Cu" "F.Paste" "F.Mask") (roundrect_rratio 0.2272727273)
      (net 1 "GND") (pinfunction "GND") (pintype "power_in"))
    (pad "11" smd roundrect (at 0.8 -0.202 90) (size 0.6 0.2) (layers "F.Cu" "F.Paste" "F.Mask") (roundrect_rratio 0.2272727273)
      (net 1 "GND") (pinfunction "GND") (pintype "passive"))
    (pad "12" smd roundrect (at 0.8 -0.6 90) (size 0.6 0.2) (layers "F.Cu" "F.Paste" "F.Mask") (roundrect_rratio 0.2272727273)
      (net 128 "/Reset logic/MIO38") (pinfunction "2B2") (pintype "bidirectional"))
    (pad "13" smd roundrect (at 0.598 -1.2 180) (size 0.6 0.2) (layers "F.Cu" "F.Paste" "F.Mask") (roundrect_rratio 0.2272727273)
      (net 130 "/Reset logic/MIO44") (pinfunction "2B1") (pintype "bidirectional"))
    (pad "14" smd roundrect (at 0.2 -1.2 180) (size 0.6 0.2) (layers "F.Cu" "F.Paste" "F.Mask") (roundrect_rratio 0.2272727273)
      (net 130 "/Reset logic/MIO44") (pinfunction "1B2") (pintype "bidirectional"))
    (pad "15" smd roundrect (at -0.202 -1.2 180) (size 0.6 0.2) (layers "F.Cu" "F.Paste" "F.Mask") (roundrect_rratio 0.2272727273)
      (net 127 "/Reset logic/MIO43") (pinfunction "1B1") (pintype "bidirectional"))
    (pad "16" smd roundrect (at -0.6 -1.2 180) (size 0.6 0.2) (layers "F.Cu" "F.Paste" "F.Mask") (roundrect_rratio 0.2272727273)
      (net 161 "/Reset logic/PS_RST") (pinfunction "2~{OE}") (pintype "input"))
  )
	(footprint "kria-k26-devboard-footprints:D_SOD-323F" (layer "F.Cu")
    (at 102.7 143.75)
    (property "Author" "Antmicro")
    (property "License" "Apache-2.0")
    (property "MPN" "1N4148WS")
    (property "Manufacturer" "ON Semiconductor")
    (property "Sheetfile" "reset.kicad_sch")
    (property "Sheetname" "Reset logic")
    (property "ki_description" "Small Signal Fast Switching Diode")
    (attr smd)
    (fp_text reference "D5" (at -0.77 1.67) (layer "F.SilkS")
        (effects (font (size 0.7 0.7) (thickness 0.15)) (justify left bottom))
    )
    (fp_text value "1N4148WS" (at -1.7 1.9) (layer "F.Fab") hide
        (effects (font (size 0.7 0.7) (thickness 0.15)) (justify left bottom))
    )
    (fp_text user "${REFERENCE}" (at -1.8 3.2) (layer "F.Fab") hide
        (effects (font (size 0.7 0.7) (thickness 0.15)) (justify left bottom))
    )
    (fp_text user "Author: Antmicro" (at -1.8 4.46) (layer "F.Fab") hide
        (effects (font (size 0.7 0.7) (thickness 0.15)) (justify left bottom))
    )
    (fp_text user "License: Apache-2.0" (at -1.8 5.8) (layer "F.Fab") hide
        (effects (font (size 0.7 0.7) (thickness 0.15)) (justify left bottom))
    )
    (fp_line (start -0.975 -0.75) (end -0.975 -0.45)
      (stroke (width 0.15) (type solid)) (layer "F.SilkS"))
    (fp_line (start -0.975 0.748) (end -0.975 0.45)
      (stroke (width 0.15) (type solid)) (layer "F.SilkS"))
    (fp_line (start -0.625 -0.75) (end -0.975 -0.75)
      (stroke (width 0.15) (type solid)) (layer "F.SilkS"))
    (fp_line (start -0.625 0.748) (end -0.975 0.748)
      (stroke (width 0.15) (type solid)) (layer "F.SilkS"))
    (fp_line (start -0.5 -0.426) (end -0.5 0.424)
      (stroke (width 0.15) (type solid)) (layer "F.SilkS"))
    (fp_line (start 0.623 -0.75) (end 0.973 -0.75)
      (stroke (width 0.15) (type solid)) (layer "F.SilkS"))
    (fp_line (start 0.973 -0.75) (end 0.973 -0.45)
      (stroke (width 0.15) (type solid)) (layer "F.SilkS"))
    (fp_line (start 0.973 0.45) (end 0.973 0.748)
      (stroke (width 0.15) (type solid)) (layer "F.SilkS"))
    (fp_line (start 0.973 0.748) (end 0.623 0.748)
      (stroke (width 0.15) (type solid)) (layer "F.SilkS"))
    (fp_rect (start -1.6 -0.827) (end 1.599 0.825)
      (stroke (width 0.05) (type solid)) (fill none) (layer "F.CrtYd"))
    (fp_line (start -0.85 -0.625) (end 0.848 -0.625)
      (stroke (width 0.15) (type solid)) (layer "F.Fab"))
    (fp_line (start -0.85 0.623) (end -0.85 -0.625)
      (stroke (width 0.15) (type solid)) (layer "F.Fab"))
    (fp_line (start -0.85 0.623) (end 0.848 0.623)
      (stroke (width 0.15) (type solid)) (layer "F.Fab"))
    (fp_line (start 0.848 -0.625) (end 0.848 0.623)
      (stroke (width 0.15) (type solid)) (layer "F.Fab"))
    (pad "A" smd roundrect (at 1.05 0) (size 0.8 0.6) (layers "F.Cu" "F.Paste" "F.Mask") (roundrect_rratio 0.15)
      (net 336 "Net-(U31-MR_N)") (pinfunction "A") (pintype "passive"))
    (pad "K" smd roundrect (at -1.051 0) (size 0.8 0.6) (layers "F.Cu" "F.Paste" "F.Mask") (roundrect_rratio 0.15)
      (net 327 "Net-(D4-PadK)") (pinfunction "K") (pintype "passive"))
  )
)
